# BASEBOARD_FAB2 (Tioga Pass) — schematic netlist excerpt (pin names and nets, part order shuffled) for the footprints in the layout excerpt that follows; sources: Cadence DE-HDL packaged netlist, KiCad conversion of Wiwynn_Tioga_Pass_MB.brd

C9R14  CAP_A  0.1UF 16V 10% X7R  pkg 0402V  page 167 : A = P3V3_STBY ; B = GND
C1R14  CAP_A  0.1UF 16V 10% X7R  pkg 0402V  page 139 : A = P3V3_STBY ; B = GND
C5G74  CAP_A  22.0UF 4V 20% X6S  pkg 0603V  page 242 : A = PVDDQ_DEF ; B = GND

(kicad_pcb
	(version 20260206)
	(generator "pcbnew")
	(generator_version "10.0")
	(general
		(thickness 1.6)
		(legacy_teardrops no)
	)
	(paper "A4")
	(title_block
		(title "Wiwynn_Tioga_Pass_MB.brd")
		(comment 1 "Tioga Pass / footprints 3243-3245 of 4770")
	)
	(layers
		(0 "F.Cu" signal "TOP")
		(4 "In1.Cu" signal "L2GND")
		(6 "In2.Cu" signal "L3")
		(8 "In3.Cu" signal "L4GND")
		(10 "In4.Cu" signal "L5")
		(12 "In5.Cu" signal "L6GND")
		(14 "In6.Cu" signal "L7VCC")
		(16 "In7.Cu" signal "L8VCC")
		(18 "In8.Cu" signal "L9GND")
		(20 "In9.Cu" signal "L10")
		(22 "In10.Cu" signal "L11GND")
		(24 "In11.Cu" signal "L12")
		(26 "In12.Cu" signal "L13GND")
		(2 "B.Cu" signal "BOTTOM")
		(9 "F.Adhes" user "F.Adhesive")
		(11 "B.Adhes" user "B.Adhesive")
		(13 "F.Paste" user "Package Geometry/Pastemask Top")
		(15 "B.Paste" user "Package Geometry/Pastemask Bottom")
		(5 "F.SilkS" user "Ref Des/Silkscreen Top")
		(7 "B.SilkS" user "Ref Des/Silkscreen Bottom")
		(1 "F.Mask" user "Board Geometry/Soldermask Top")
		(3 "B.Mask" user "Board Geometry/Soldermask Bottom")
		(17 "Dwgs.User" user "User.Drawings")
		(19 "Cmts.User" user "User.Comments")
		(21 "Eco1.User" user "User.Eco1")
		(23 "Eco2.User" user "User.Eco2")
		(25 "Edge.Cuts" user "Board Geometry/Outline")
		(27 "Margin" user)
		(31 "F.CrtYd" user "Package Geometry/Place Bound Top")
		(29 "B.CrtYd" user "Package Geometry/Place Bound Bottom")
		(35 "F.Fab" user "Ref Des/Assembly Top")
		(33 "B.Fab" user "Ref Des/Assembly Bottom")
	)
	(footprint ""
		(layer "B.Cu")
		(at 484.0732 -48.5267)
		(property "Reference" "C1R14"
			(at 0 0 0)
			(layer "B.SilkS")
			(hide yes)
			(effects
				(font
					(size 1.27 1.27)
				)
				(justify mirror)
			)
		)
		(property "Value" ""
			(at 0 0 0)
			(layer "B.Fab")
			(effects
				(font
					(size 1.27 1.27)
				)
				(justify mirror)
			)
		)
		(duplicate_pad_numbers_are_jumpers no)
		(fp_poly
			(pts
				(xy -0.3048 -0.1016) (xy -0.3048 0.9906) (xy 0.3048 0.9906) (xy 0.3048 -0.1016)
			)
			(stroke
				(width 0)
				(type default)
			)
			(fill no)
			(layer "B.CrtYd")
		)
		(fp_line
			(start -0.3048 -0.1016)
			(end 0.3048 -0.1016)
			(stroke
				(width 0.1)
				(type default)
			)
			(layer "B.Fab")
		)
		(fp_line
			(start -0.3048 0.9906)
			(end -0.3048 -0.1016)
			(stroke
				(width 0.1)
				(type default)
			)
			(layer "B.Fab")
		)
		(fp_line
			(start 0.3048 -0.1016)
			(end 0.3048 0.9906)
			(stroke
				(width 0.1)
				(type default)
			)
			(layer "B.Fab")
		)
		(fp_line
			(start 0.3048 0.9906)
			(end -0.3048 0.9906)
			(stroke
				(width 0.1)
				(type default)
			)
			(layer "B.Fab")
		)
		(pad "1" smd rect
			(at 0 0 180)
			(size 0.508 0.508)
			(layers "B.Cu" "B.Mask" "B.Paste")
			(net "P3V3_STBY")
		)
		(pad "2" smd rect
			(at 0 0.889 180)
			(size 0.508 0.508)
			(layers "B.Cu" "B.Mask" "B.Paste")
			(net "GND")
		)
		(zone
			(layer "B.Cu")
			(hatch none 0.5)
			(connect_pads
				(clearance 0)
			)
			(min_thickness 0.25)
			(keepout
				(tracks allowed)
				(vias not_allowed)
				(pads allowed)
				(copperpour not_allowed)
				(footprints allowed)
			)
			(placement
				(enabled no)
				(sheetname "")
			)
			(fill
				(thermal_gap 0.5)
				(thermal_bridge_width 0.5)
				(island_removal_mode 0)
			)
			(polygon
				(pts
					(xy 484.3272 -48.2727) (xy 483.8192 -48.2727) (xy 483.8192 -47.8917) (xy 484.3272 -47.8917)
				)
			)
		)
		(zone
			(layer "B.Cu")
			(hatch none 0.5)
			(connect_pads
				(clearance 0)
			)
			(min_thickness 0.25)
			(keepout
				(tracks not_allowed)
				(vias allowed)
				(pads allowed)
				(copperpour not_allowed)
				(footprints allowed)
			)
			(placement
				(enabled no)
				(sheetname "")
			)
			(fill
				(thermal_gap 0.5)
				(thermal_bridge_width 0.5)
				(island_removal_mode 0)
			)
			(polygon
				(pts
					(xy 484.3272 -47.8917) (xy 483.8192 -47.8917) (xy 483.8192 -48.2727) (xy 484.3272 -48.2727)
				)
			)
		)
	)
	(footprint ""
		(layer "B.Cu")
		(at 18.161 -45.72)
		(property "Reference" "C9R14"
			(at 0 0 0)
			(layer "B.SilkS")
			(hide yes)
			(effects
				(font
					(size 1.27 1.27)
				)
				(justify mirror)
			)
		)
		(property "Value" ""
			(at 0 0 0)
			(layer "B.Fab")
			(effects
				(font
					(size 1.27 1.27)
				)
				(justify mirror)
			)
		)
		(duplicate_pad_numbers_are_jumpers no)
		(fp_poly
			(pts
				(xy -0.3048 -0.1016) (xy -0.3048 0.9906) (xy 0.3048 0.9906) (xy 0.3048 -0.1016)
			)
			(stroke
				(width 0)
				(type default)
			)
			(fill no)
			(layer "B.CrtYd")
		)
		(fp_line
			(start -0.3048 -0.1016)
			(end 0.3048 -0.1016)
			(stroke
				(width 0.1)
				(type default)
			)
			(layer "B.Fab")
		)
		(fp_line
			(start -0.3048 0.9906)
			(end -0.3048 -0.1016)
			(stroke
				(width 0.1)
				(type default)
			)
			(layer "B.Fab")
		)
		(fp_line
			(start 0.3048 -0.1016)
			(end 0.3048 0.9906)
			(stroke
				(width 0.1)
				(type default)
			)
			(layer "B.Fab")
		)
		(fp_line
			(start 0.3048 0.9906)
			(end -0.3048 0.9906)
			(stroke
				(width 0.1)
				(type default)
			)
			(layer "B.Fab")
		)
		(pad "1" smd rect
			(at 0 0 180)
			(size 0.508 0.508)
			(layers "B.Cu" "B.Mask" "B.Paste")
			(net "P3V3_STBY")
		)
		(pad "2" smd rect
			(at 0 0.889 180)
			(size 0.508 0.508)
			(layers "B.Cu" "B.Mask" "B.Paste")
			(net "GND")
		)
		(zone
			(layer "B.Cu")
			(hatch none 0.5)
			(connect_pads
				(clearance 0)
			)
			(min_thickness 0.25)
			(keepout
				(tracks allowed)
				(vias not_allowed)
				(pads allowed)
				(copperpour not_allowed)
				(footprints allowed)
			)
			(placement
				(enabled no)
				(sheetname "")
			)
			(fill
				(thermal_gap 0.5)
				(thermal_bridge_width 0.5)
				(island_removal_mode 0)
			)
			(polygon
				(pts
					(xy 18.415 -45.466) (xy 17.907 -45.466) (xy 17.907 -45.085) (xy 18.415 -45.085)
				)
			)
		)
		(zone
			(layer "B.Cu")
			(hatch none 0.5)
			(connect_pads
				(clearance 0)
			)
			(min_thickness 0.25)
			(keepout
				(tracks not_allowed)
				(vias allowed)
				(pads allowed)
				(copperpour not_allowed)
				(footprints allowed)
			)
			(placement
				(enabled no)
				(sheetname "")
			)
			(fill
				(thermal_gap 0.5)
				(thermal_bridge_width 0.5)
				(island_removal_mode 0)
			)
			(polygon
				(pts
					(xy 18.415 -45.085) (xy 17.907 -45.085) (xy 17.907 -45.466) (xy 18.415 -45.466)
				)
			)
		)
	)
	(footprint ""
		(layer "B.Cu")
		(at 269.559532 -140.208 90)
		(property "Reference" "C5G74"
			(at -1.14681 0.76708 180)
			(unlocked yes)
			(layer "B.SilkS")
			(effects
				(font
					(size 0.7874 0.5842)
					(thickness 0.1524)
				)
				(justify mirror)
			)
		)
		(property "Value" ""
			(at 0 0 90)
			(layer "B.Fab")
			(effects
				(font
					(size 1.27 1.27)
				)
				(justify mirror)
			)
		)
		(duplicate_pad_numbers_are_jumpers no)
		(fp_rect
			(start -0.4953 -0.2032)
			(end 0.4953 1.6002)
			(stroke
				(width 0)
				(type default)
			)
			(fill no)
			(layer "B.CrtYd")
		)
		(fp_line
			(start 0.4953 -0.2032)
			(end -0.4953 -0.2032)
			(stroke
				(width 0.1)
				(type default)
			)
			(layer "B.Fab")
		)
		(fp_line
			(start -0.4953 -0.2032)
			(end -0.4953 1.6002)
			(stroke
				(width 0.1)
				(type default)
			)
			(layer "B.Fab")
		)
		(fp_line
			(start 0.4953 1.6002)
			(end 0.4953 -0.2032)
			(stroke
				(width 0.1)
				(type default)
			)
			(layer "B.Fab")
		)
		(fp_line
			(start -0.4953 1.6002)
			(end 0.4953 1.6002)
			(stroke
				(width 0.1)
				(type default)
			)
			(layer "B.Fab")
		)
		(pad "1" smd rect
			(at 0 0 270)
			(size 0.762 0.889)
			(layers "B.Cu" "B.Mask" "B.Paste")
			(net "PVDDQ_DEF")
		)
		(pad "2" smd rect
			(at 0 1.397 270)
			(size 0.762 0.889)
			(layers "B.Cu" "B.Mask" "B.Paste")
			(net "GND")
		)
		(zone
			(layer "B.Cu")
			(hatch none 0.5)
			(connect_pads
				(clearance 0)
			)
			(min_thickness 0.25)
			(keepout
				(tracks not_allowed)
				(vias allowed)
				(pads allowed)
				(copperpour not_allowed)
				(footprints allowed)
			)
			(placement
				(enabled no)
				(sheetname "")
			)
			(fill
				(thermal_gap 0.5)
				(thermal_bridge_width 0.5)
				(island_removal_mode 0)
			)
			(polygon
				(pts
					(xy 270.004032 -139.827) (xy 270.512032 -139.827) (xy 270.512032 -140.589) (xy 270.004032 -140.589)
				)
			)
		)
	)
)
